# S9S_MB_2U (Grand Teton) — schematic netlist excerpt (pin names and nets, part order shuffled) for the footprints in the layout excerpt that follows; sources: Cadence DE-HDL packaged netlist, KiCad conversion of 03242023_DA0F0TMBIJ0_F0T_Motherboard_J_brd_V01_OCP.brd

R4292  Q_RES  4.7K 1% EMPTY  pkg 0402LF  page 169 : A = FM_USB3_1_EN_N ; B = GND
PC291_P0_3  Q_CAP  22UF 4V 20% X6S  pkg C0805  page 268 : A = PVCCIN_CPU0 ; B = GND

(kicad_pcb
	(version 20260206)
	(generator "pcbnew")
	(generator_version "10.0")
	(general
		(thickness 1.6)
		(legacy_teardrops no)
	)
	(paper "A4")
	(title_block
		(title "03242023_DA0F0TMBIJ0_F0T_Motherboard_J_brd_V01_OCP.brd")
		(comment 1 "Grand Teton / footprints 6053-6054 of 6105")
	)
	(layers
		(0 "F.Cu" signal "TOP")
		(4 "In1.Cu" signal "GND")
		(6 "In2.Cu" signal "IN1")
		(8 "In3.Cu" signal "GND1")
		(10 "In4.Cu" signal "IN2")
		(12 "In5.Cu" signal "GND2")
		(14 "In6.Cu" signal "IN3")
		(16 "In7.Cu" signal "GND3")
		(18 "In8.Cu" signal "VCC")
		(20 "In9.Cu" signal "VCC1")
		(22 "In10.Cu" signal "GND4")
		(24 "In11.Cu" signal "IN4")
		(26 "In12.Cu" signal "GND5")
		(28 "In13.Cu" signal "IN5")
		(30 "In14.Cu" signal "GND6")
		(32 "In15.Cu" signal "IN6")
		(34 "In16.Cu" signal "GND7")
		(2 "B.Cu" signal "BOTTOM")
		(9 "F.Adhes" user "F.Adhesive")
		(11 "B.Adhes" user "B.Adhesive")
		(13 "F.Paste" user "Package Geometry/Pastemask Top")
		(15 "B.Paste" user "Package Geometry/Pastemask Bottom")
		(5 "F.SilkS" user "Ref Des/Silkscreen Top")
		(7 "B.SilkS" user "Ref Des/Silkscreen Bottom")
		(1 "F.Mask" user "Board Geometry/Soldermask Top")
		(3 "B.Mask" user "Board Geometry/Soldermask Bottom")
		(17 "Dwgs.User" user "User.Drawings")
		(19 "Cmts.User" user "User.Comments")
		(21 "Eco1.User" user "User.Eco1")
		(23 "Eco2.User" user "User.Eco2")
		(25 "Edge.Cuts" user "Board Geometry/Outline")
		(27 "Margin" user)
		(31 "F.CrtYd" user "Package Geometry/Place Bound Top")
		(29 "B.CrtYd" user "Package Geometry/Place Bound Bottom")
		(35 "F.Fab" user "Ref Des/Assembly Top")
		(33 "B.Fab" user "Ref Des/Assembly Bottom")
	)
	(footprint ""
		(layer "B.Cu")
		(at 126.89586 -22.794468 90)
		(property "Reference" "R4292"
			(at 0 0 90)
			(layer "B.SilkS")
			(hide yes)
			(effects
				(font
					(size 1.27 1.27)
				)
				(justify mirror)
			)
		)
		(property "Value" ""
			(at 0 0 90)
			(layer "B.Fab")
			(effects
				(font
					(size 1.27 1.27)
				)
				(justify mirror)
			)
		)
		(duplicate_pad_numbers_are_jumpers no)
		(fp_line
			(start 0.7874 -0.4064)
			(end -0.7874 -0.4064)
			(stroke
				(width 0.1524)
				(type default)
			)
			(layer "B.SilkS")
		)
		(fp_line
			(start -0.7874 -0.4064)
			(end -0.7874 0.4064)
			(stroke
				(width 0.1524)
				(type default)
			)
			(layer "B.SilkS")
		)
		(fp_line
			(start 0.7874 0.4064)
			(end 0.7874 -0.4064)
			(stroke
				(width 0.1524)
				(type default)
			)
			(layer "B.SilkS")
		)
		(fp_line
			(start -0.7874 0.4064)
			(end 0.7874 0.4064)
			(stroke
				(width 0.1524)
				(type default)
			)
			(layer "B.SilkS")
		)
		(fp_line
			(start 0.67945 -0.305054)
			(end 0.12065 -0.305054)
			(stroke
				(width 0.1)
				(type default)
			)
			(layer "B.Fab")
		)
		(fp_line
			(start 0.12065 -0.305054)
			(end 0.12065 -0.2794)
			(stroke
				(width 0.1)
				(type default)
			)
			(layer "B.Fab")
		)
		(fp_line
			(start -0.12065 -0.3048)
			(end -0.67945 -0.3048)
			(stroke
				(width 0.1)
				(type default)
			)
			(layer "B.Fab")
		)
		(fp_line
			(start -0.67945 -0.3048)
			(end -0.67945 0.3048)
			(stroke
				(width 0.1)
				(type default)
			)
			(layer "B.Fab")
		)
		(fp_line
			(start 0.12065 -0.2794)
			(end -0.12065 -0.2794)
			(stroke
				(width 0.1)
				(type default)
			)
			(layer "B.Fab")
		)
		(fp_line
			(start -0.12065 -0.2794)
			(end -0.12065 -0.3048)
			(stroke
				(width 0.1)
				(type default)
			)
			(layer "B.Fab")
		)
		(fp_line
			(start 0.12065 0.2794)
			(end 0.12065 0.3048)
			(stroke
				(width 0.1)
				(type default)
			)
			(layer "B.Fab")
		)
		(fp_line
			(start -0.120396 0.2794)
			(end 0.12065 0.2794)
			(stroke
				(width 0.1)
				(type default)
			)
			(layer "B.Fab")
		)
		(fp_line
			(start 0.67945 0.3048)
			(end 0.67945 -0.305054)
			(stroke
				(width 0.1)
				(type default)
			)
			(layer "B.Fab")
		)
		(fp_line
			(start 0.12065 0.3048)
			(end 0.67945 0.3048)
			(stroke
				(width 0.1)
				(type default)
			)
			(layer "B.Fab")
		)
		(fp_line
			(start -0.120396 0.3048)
			(end -0.120396 0.2794)
			(stroke
				(width 0.1)
				(type default)
			)
			(layer "B.Fab")
		)
		(fp_line
			(start -0.67945 0.3048)
			(end -0.120396 0.3048)
			(stroke
				(width 0.1)
				(type default)
			)
			(layer "B.Fab")
		)
		(pad "1" smd circle
			(at 0.40005 0 270)
			(size 0 0)
			(layers "B.Cu" "B.Mask" "B.Paste")
			(net "FM_USB3_1_EN_N")
		)
		(pad "2" smd circle
			(at -0.40005 0 270)
			(size 0 0)
			(layers "B.Cu" "B.Mask" "B.Paste")
			(net "GND")
		)
	)
	(footprint ""
		(layer "B.Cu")
		(at 365.438436 -324.911466 -90)
		(property "Reference" "PC291_P0_3"
			(at 0 0 90)
			(layer "B.SilkS")
			(hide yes)
			(effects
				(font
					(size 1.27 1.27)
				)
				(justify mirror)
			)
		)
		(property "Value" ""
			(at 0 0 90)
			(layer "B.Fab")
			(effects
				(font
					(size 1.27 1.27)
				)
				(justify mirror)
			)
		)
		(duplicate_pad_numbers_are_jumpers no)
		(fp_line
			(start -1.524 0.762)
			(end 1.524 0.762)
			(stroke
				(width 0.1524)
				(type default)
			)
			(layer "B.SilkS")
		)
		(fp_line
			(start 1.524 0.762)
			(end 1.524 -0.762)
			(stroke
				(width 0.1524)
				(type default)
			)
			(layer "B.SilkS")
		)
		(fp_line
			(start -1.524 -0.762)
			(end -1.524 0.762)
			(stroke
				(width 0.1524)
				(type default)
			)
			(layer "B.SilkS")
		)
		(fp_line
			(start 1.524 -0.762)
			(end -1.524 -0.762)
			(stroke
				(width 0.1524)
				(type default)
			)
			(layer "B.SilkS")
		)
		(fp_line
			(start -1.1049 0.724916)
			(end -1.1049 -0.724916)
			(stroke
				(width 0.1)
				(type default)
			)
			(layer "B.Fab")
		)
		(fp_line
			(start 1.1049 0.724916)
			(end -1.1049 0.724916)
			(stroke
				(width 0.1)
				(type default)
			)
			(layer "B.Fab")
		)
		(fp_line
			(start -1.1049 -0.724916)
			(end 1.1049 -0.724916)
			(stroke
				(width 0.1)
				(type default)
			)
			(layer "B.Fab")
		)
		(fp_line
			(start 1.1049 -0.724916)
			(end 1.1049 0.724916)
			(stroke
				(width 0.1)
				(type default)
			)
			(layer "B.Fab")
		)
		(pad "1" smd rect
			(at 0.889 0 270)
			(size 1.016 1.27)
			(layers "B.Cu" "B.Mask" "B.Paste")
			(net "PVCCIN_CPU0")
		)
		(pad "2" smd rect
			(at -0.889 0 270)
			(size 1.016 1.27)
			(layers "B.Cu" "B.Mask" "B.Paste")
			(net "GND")
		)
	)
)
